(kicad_pcb
	(version 20260206)
	(generator "pcbnew")
	(generator_version "10.0")
	(general
		(thickness 1.6)
		(legacy_teardrops no)
	)
	(paper "A4")
	(title_block
		(title "panther-plus-userver — 13130-1b_20150205.brd")
		(comment 1 "Honey Badger (Wiwynn) / footprints 927-933 of 1509")
	)
	(layers
		(0 "F.Cu" signal "TOP")
		(4 "In1.Cu" signal "L2")
		(6 "In2.Cu" signal "L3")
		(8 "In3.Cu" signal "L4")
		(10 "In4.Cu" signal "L5")
		(12 "In5.Cu" signal "L6")
		(14 "In6.Cu" signal "L7")
		(16 "In7.Cu" signal "L8")
		(18 "In8.Cu" signal "L9")
		(20 "In9.Cu" signal "L10")
		(22 "In10.Cu" signal "L11")
		(2 "B.Cu" signal "BOTTOM")
		(9 "F.Adhes" user "F.Adhesive")
		(11 "B.Adhes" user "B.Adhesive")
		(13 "F.Paste" user "Package Geometry/Pastemask Top")
		(15 "B.Paste" user "Package Geometry/Pastemask Bottom")
		(5 "F.SilkS" user "Ref Des/Silkscreen Top")
		(7 "B.SilkS" user "Ref Des/Silkscreen Bottom")
		(1 "F.Mask" user "Board Geometry/Soldermask Top")
		(3 "B.Mask" user "Board Geometry/Soldermask Bottom")
		(17 "Dwgs.User" user "User.Drawings")
		(19 "Cmts.User" user "User.Comments")
		(21 "Eco1.User" user "User.Eco1")
		(23 "Eco2.User" user "User.Eco2")
		(25 "Edge.Cuts" user "Board Geometry/Outline")
		(27 "Margin" user)
		(31 "F.CrtYd" user "Package Geometry/Place Bound Top")
		(29 "B.CrtYd" user "Package Geometry/Place Bound Bottom")
		(35 "F.Fab" user "Ref Des/Assembly Top")
		(33 "B.Fab" user "Ref Des/Assembly Bottom")
	)
	(footprint ""
		(layer "B.Cu")
		(at 74.168 -46.101 90)
		(property "Reference" "R292"
			(at 0 0 90)
			(layer "B.SilkS")
			(hide yes)
			(effects
				(font
					(size 1.27 1.27)
				)
				(justify mirror)
			)
		)
		(property "Value" "22R2F-1-GP"
			(at -0.064008 -3.993896 90)
			(unlocked yes)
			(layer "B.Fab")
			(hide yes)
			(effects
				(font
					(size 1.016 1.016)
					(thickness 0.1524)
				)
				(justify mirror)
			)
		)
		(property "Device Type" "R402H16"
			(at -0.064008 -5.517896 90)
			(unlocked yes)
			(layer "B.Fab")
			(hide yes)
			(effects
				(font
					(size 1.016 1.016)
					(thickness 0.1524)
				)
				(justify mirror)
			)
		)
		(duplicate_pad_numbers_are_jumpers no)
		(fp_rect
			(start 0.381 0.8382)
			(end -0.381 -0.8382)
			(stroke
				(width 0)
				(type default)
			)
			(fill no)
			(layer "B.CrtYd")
		)
		(fp_rect
			(start 0.381 0.8382)
			(end -0.381 -0.8382)
			(stroke
				(width 0)
				(type default)
			)
			(fill no)
			(layer "B.Fab")
		)
		(pad "1" smd custom
			(at 0 -0.4318 270)
			(size 0.127 0.127)
			(layers "B.Cu" "B.Mask" "B.Paste")
			(net "PMU_RESETBUTTON#")
			(options
				(clearance outline)
				(anchor circle)
			)
			(primitives
				(gr_poly
					(pts
						(arc
							(start -0.2032 0.2794)
							(mid -0.239121 0.264521)
							(end -0.254 0.2286)
						)
						(arc
							(start -0.254 -0.2286)
							(mid -0.239121 -0.264521)
							(end -0.2032 -0.2794)
						)
						(arc
							(start 0.2032 -0.2794)
							(mid 0.239121 -0.264521)
							(end 0.254 -0.2286)
						)
						(arc
							(start 0.254 0.2286)
							(mid 0.239121 0.264521)
							(end 0.2032 0.2794)
						)
					)
					(width 0)
					(fill yes)
				)
			)
		)
		(pad "2" smd custom
			(at 0 0.4318 270)
			(size 0.127 0.127)
			(layers "B.Cu" "B.Mask" "B.Paste")
			(net "PMU_RESETBUTTON_R#")
			(options
				(clearance outline)
				(anchor circle)
			)
			(primitives
				(gr_poly
					(pts
						(arc
							(start -0.2032 0.2794)
							(mid -0.239121 0.264521)
							(end -0.254 0.2286)
						)
						(arc
							(start -0.254 -0.2286)
							(mid -0.239121 -0.264521)
							(end -0.2032 -0.2794)
						)
						(arc
							(start 0.2032 -0.2794)
							(mid 0.239121 -0.264521)
							(end 0.254 -0.2286)
						)
						(arc
							(start 0.254 0.2286)
							(mid 0.239121 0.264521)
							(end 0.2032 0.2794)
						)
					)
					(width 0)
					(fill yes)
				)
			)
		)
	)
	(footprint ""
		(layer "B.Cu")
		(at 84.709 -62.865)
		(property "Reference" "Q12"
			(at 0 0 0)
			(layer "B.SilkS")
			(hide yes)
			(effects
				(font
					(size 1.27 1.27)
				)
				(justify mirror)
			)
		)
		(property "Value" "MMBT3904TT1G-GP"
			(at 0 -9.7282 0)
			(unlocked yes)
			(layer "B.Fab")
			(hide yes)
			(effects
				(font
					(size 1.016 1.016)
					(thickness 0.1524)
				)
				(justify mirror)
			)
		)
		(property "Device Type" "SC75CBE1D6H36"
			(at 0 -11.6332 0)
			(unlocked yes)
			(layer "B.Fab")
			(hide yes)
			(effects
				(font
					(size 1.016 1.016)
					(thickness 0.1524)
				)
				(justify mirror)
			)
		)
		(duplicate_pad_numbers_are_jumpers no)
		(fp_poly
			(pts
				(xy -0.381 -1.1938) (xy 0.381 -1.1938) (xy 0.381 -0.6604) (xy 1.0541 -0.6604) (xy 1.0541 0.6604)
				(xy 0.889 0.6604) (xy 0.889 1.1938) (xy -0.889 1.1938) (xy -0.889 0.6604) (xy -1.0541 0.6604) (xy -1.0541 -0.6604)
				(xy -0.381 -0.6604)
			)
			(stroke
				(width 0)
				(type default)
			)
			(fill no)
			(layer "B.CrtYd")
		)
		(fp_poly
			(pts
				(xy -0.381 -1.1938) (xy 0.381 -1.1938) (xy 0.381 -0.6604) (xy 1.0541 -0.6604) (xy 1.0541 0.6604)
				(xy 0.889 0.6604) (xy 0.889 1.1938) (xy -0.889 1.1938) (xy -0.889 0.6604) (xy -1.0541 0.6604) (xy -1.0541 -0.6604)
				(xy -0.381 -0.6604)
			)
			(stroke
				(width 0)
				(type default)
			)
			(fill no)
			(layer "B.Fab")
		)
		(pad "B" smd custom
			(at 0.508 0.6604 180)
			(size 0.127 0.127)
			(layers "B.Cu" "B.Mask" "B.Paste")
			(net "H_PROCESSOR_HOT_N_R")
			(options
				(clearance outline)
				(anchor circle)
			)
			(primitives
				(gr_poly
					(pts
						(arc
							(start -0.0508 -0.4064)
							(mid -0.194484 -0.346884)
							(end -0.254 -0.2032)
						)
						(arc
							(start -0.254 0.2032)
							(mid -0.194484 0.346884)
							(end -0.0508 0.4064)
						)
						(arc
							(start 0.0508 0.4064)
							(mid 0.194484 0.346884)
							(end 0.254 0.2032)
						)
						(arc
							(start 0.254 -0.2032)
							(mid 0.194484 -0.346884)
							(end 0.0508 -0.4064)
						)
					)
					(width 0)
					(fill yes)
				)
			)
		)
		(pad "C" smd custom
			(at 0 -0.6604 180)
			(size 0.127 0.127)
			(layers "B.Cu" "B.Mask" "B.Paste")
			(net "PROCESSOR_HOT_LVC#")
			(options
				(clearance outline)
				(anchor circle)
			)
			(primitives
				(gr_poly
					(pts
						(arc
							(start -0.0508 -0.4064)
							(mid -0.194484 -0.346884)
							(end -0.254 -0.2032)
						)
						(arc
							(start -0.254 0.2032)
							(mid -0.194484 0.346884)
							(end -0.0508 0.4064)
						)
						(arc
							(start 0.0508 0.4064)
							(mid 0.194484 0.346884)
							(end 0.254 0.2032)
						)
						(arc
							(start 0.254 -0.2032)
							(mid 0.194484 -0.346884)
							(end 0.0508 -0.4064)
						)
					)
					(width 0)
					(fill yes)
				)
			)
		)
		(pad "E" smd custom
			(at -0.508 0.6604 180)
			(size 0.127 0.127)
			(layers "B.Cu" "B.Mask" "B.Paste")
			(net "PROCESSOR_HOT#")
			(options
				(clearance outline)
				(anchor circle)
			)
			(primitives
				(gr_poly
					(pts
						(arc
							(start -0.0508 -0.4064)
							(mid -0.194484 -0.346884)
							(end -0.254 -0.2032)
						)
						(arc
							(start -0.254 0.2032)
							(mid -0.194484 0.346884)
							(end -0.0508 0.4064)
						)
						(arc
							(start 0.0508 0.4064)
							(mid 0.194484 0.346884)
							(end 0.254 0.2032)
						)
						(arc
							(start 0.254 -0.2032)
							(mid 0.194484 -0.346884)
							(end 0.0508 -0.4064)
						)
					)
					(width 0)
					(fill yes)
				)
			)
		)
	)
	(footprint ""
		(layer "B.Cu")
		(at 105.156 -19.177)
		(property "Reference" "C255"
			(at 0 0 0)
			(layer "B.SilkS")
			(hide yes)
			(effects
				(font
					(size 1.27 1.27)
				)
				(justify mirror)
			)
		)
		(property "Value" "SC10U6D3V3MX-GP"
			(at 0 -2.8194 0)
			(unlocked yes)
			(layer "B.Fab")
			(hide yes)
			(effects
				(font
					(size 1.016 1.016)
					(thickness 0.1524)
				)
				(justify mirror)
			)
		)
		(property "Device Type" "C603H38"
			(at 0 -4.3434 0)
			(unlocked yes)
			(layer "B.Fab")
			(hide yes)
			(effects
				(font
					(size 1.016 1.016)
					(thickness 0.1524)
				)
				(justify mirror)
			)
		)
		(duplicate_pad_numbers_are_jumpers no)
		(fp_line
			(start 0.4064 0)
			(end -0.4064 0)
			(stroke
				(width 0.2286)
				(type default)
			)
			(layer "B.SilkS")
		)
		(fp_rect
			(start 0.635 1.1811)
			(end -0.635 -1.1811)
			(stroke
				(width 0)
				(type default)
			)
			(fill no)
			(layer "B.CrtYd")
		)
		(fp_rect
			(start 0.635 1.1811)
			(end -0.635 -1.1811)
			(stroke
				(width 0)
				(type default)
			)
			(fill no)
			(layer "B.Fab")
		)
		(pad "1" smd custom
			(at 0 -0.6604 180)
			(size 0.19685 0.19685)
			(layers "B.Cu" "B.Mask" "B.Paste")
			(net "VCCCLKDDR1")
			(options
				(clearance outline)
				(anchor circle)
			)
			(primitives
				(gr_poly
					(pts
						(arc
							(start 0.508 0.2921)
							(mid 0.478242 0.363942)
							(end 0.4064 0.3937)
						)
						(arc
							(start -0.4064 0.3937)
							(mid -0.478242 0.363942)
							(end -0.508 0.2921)
						)
						(arc
							(start -0.508 -0.2921)
							(mid -0.478242 -0.363942)
							(end -0.4064 -0.3937)
						)
						(arc
							(start 0.4064 -0.3937)
							(mid 0.478242 -0.363942)
							(end 0.508 -0.2921)
						)
					)
					(width 0)
					(fill yes)
				)
			)
		)
		(pad "2" smd custom
			(at 0 0.6604 180)
			(size 0.19685 0.19685)
			(layers "B.Cu" "B.Mask" "B.Paste")
			(net "GND")
			(options
				(clearance outline)
				(anchor circle)
			)
			(primitives
				(gr_poly
					(pts
						(arc
							(start 0.508 0.2921)
							(mid 0.478242 0.363942)
							(end 0.4064 0.3937)
						)
						(arc
							(start -0.4064 0.3937)
							(mid -0.478242 0.363942)
							(end -0.508 0.2921)
						)
						(arc
							(start -0.508 -0.2921)
							(mid -0.478242 -0.363942)
							(end -0.4064 -0.3937)
						)
						(arc
							(start 0.4064 -0.3937)
							(mid 0.478242 -0.363942)
							(end 0.508 -0.2921)
						)
					)
					(width 0)
					(fill yes)
				)
			)
		)
	)
	(footprint ""
		(layer "B.Cu")
		(at 74.041 -33.274 90)
		(property "Reference" "R108"
			(at 0 0 90)
			(layer "B.SilkS")
			(hide yes)
			(effects
				(font
					(size 1.27 1.27)
				)
				(justify mirror)
			)
		)
		(property "Value" "4K7R2F-GP"
			(at -0.064008 -3.993896 90)
			(unlocked yes)
			(layer "B.Fab")
			(hide yes)
			(effects
				(font
					(size 1.016 1.016)
					(thickness 0.1524)
				)
				(justify mirror)
			)
		)
		(property "Device Type" "R402H16"
			(at -0.064008 -5.517896 90)
			(unlocked yes)
			(layer "B.Fab")
			(hide yes)
			(effects
				(font
					(size 1.016 1.016)
					(thickness 0.1524)
				)
				(justify mirror)
			)
		)
		(duplicate_pad_numbers_are_jumpers no)
		(fp_rect
			(start 0.381 0.8382)
			(end -0.381 -0.8382)
			(stroke
				(width 0)
				(type default)
			)
			(fill no)
			(layer "B.CrtYd")
		)
		(fp_rect
			(start 0.381 0.8382)
			(end -0.381 -0.8382)
			(stroke
				(width 0)
				(type default)
			)
			(fill no)
			(layer "B.Fab")
		)
		(pad "1" smd custom
			(at 0 -0.4318 270)
			(size 0.127 0.127)
			(layers "B.Cu" "B.Mask" "B.Paste")
			(net "P3V3_CPU")
			(options
				(clearance outline)
				(anchor circle)
			)
			(primitives
				(gr_poly
					(pts
						(arc
							(start -0.2032 0.2794)
							(mid -0.239121 0.264521)
							(end -0.254 0.2286)
						)
						(arc
							(start -0.254 -0.2286)
							(mid -0.239121 -0.264521)
							(end -0.2032 -0.2794)
						)
						(arc
							(start 0.2032 -0.2794)
							(mid 0.239121 -0.264521)
							(end 0.254 -0.2286)
						)
						(arc
							(start 0.254 0.2286)
							(mid 0.239121 0.264521)
							(end 0.2032 0.2794)
						)
					)
					(width 0)
					(fill yes)
				)
			)
		)
		(pad "2" smd custom
			(at 0 0.4318 270)
			(size 0.127 0.127)
			(layers "B.Cu" "B.Mask" "B.Paste")
			(net "CPU_FPGA_DISABLE")
			(options
				(clearance outline)
				(anchor circle)
			)
			(primitives
				(gr_poly
					(pts
						(arc
							(start -0.2032 0.2794)
							(mid -0.239121 0.264521)
							(end -0.254 0.2286)
						)
						(arc
							(start -0.254 -0.2286)
							(mid -0.239121 -0.264521)
							(end -0.2032 -0.2794)
						)
						(arc
							(start 0.2032 -0.2794)
							(mid 0.239121 -0.264521)
							(end 0.254 -0.2286)
						)
						(arc
							(start 0.254 0.2286)
							(mid 0.239121 0.264521)
							(end 0.2032 0.2794)
						)
					)
					(width 0)
					(fill yes)
				)
			)
		)
	)
	(footprint ""
		(layer "B.Cu")
		(at 118.999 -65.151 180)
		(property "Reference" "R498"
			(at 0 0 0)
			(layer "B.SilkS")
			(hide yes)
			(effects
				(font
					(size 1.27 1.27)
				)
				(justify mirror)
			)
		)
		(property "Value" "4K7R2F-GP"
			(at -1.7907 -1.1176 180)
			(unlocked yes)
			(layer "B.Fab")
			(hide yes)
			(effects
				(font
					(size 1.016 1.016)
					(thickness 0.1524)
				)
				(justify mirror)
			)
		)
		(property "Device Type" "R402H16"
			(at -1.7907 -2.6416 180)
			(unlocked yes)
			(layer "B.Fab")
			(hide yes)
			(effects
				(font
					(size 1.016 1.016)
					(thickness 0.1524)
				)
				(justify mirror)
			)
		)
		(duplicate_pad_numbers_are_jumpers no)
		(fp_rect
			(start 0.381 0.8382)
			(end -0.381 -0.8382)
			(stroke
				(width 0)
				(type default)
			)
			(fill no)
			(layer "B.CrtYd")
		)
		(fp_rect
			(start 0.381 0.8382)
			(end -0.381 -0.8382)
			(stroke
				(width 0)
				(type default)
			)
			(fill no)
			(layer "B.Fab")
		)
		(pad "1" smd custom
			(at 0 -0.4318)
			(size 0.127 0.127)
			(layers "B.Cu" "B.Mask" "B.Paste")
			(net "P3V3_STBY")
			(options
				(clearance outline)
				(anchor circle)
			)
			(primitives
				(gr_poly
					(pts
						(arc
							(start -0.2032 0.2794)
							(mid -0.239121 0.264521)
							(end -0.254 0.2286)
						)
						(arc
							(start -0.254 -0.2286)
							(mid -0.239121 -0.264521)
							(end -0.2032 -0.2794)
						)
						(arc
							(start 0.2032 -0.2794)
							(mid 0.239121 -0.264521)
							(end 0.254 -0.2286)
						)
						(arc
							(start 0.254 0.2286)
							(mid 0.239121 0.264521)
							(end 0.2032 0.2794)
						)
					)
					(width 0)
					(fill yes)
				)
			)
		)
		(pad "2" smd custom
			(at 0 0.4318)
			(size 0.127 0.127)
			(layers "B.Cu" "B.Mask" "B.Paste")
			(net "SMB_HOST_LV_CLK")
			(options
				(clearance outline)
				(anchor circle)
			)
			(primitives
				(gr_poly
					(pts
						(arc
							(start -0.2032 0.2794)
							(mid -0.239121 0.264521)
							(end -0.254 0.2286)
						)
						(arc
							(start -0.254 -0.2286)
							(mid -0.239121 -0.264521)
							(end -0.2032 -0.2794)
						)
						(arc
							(start 0.2032 -0.2794)
							(mid 0.239121 -0.264521)
							(end 0.254 -0.2286)
						)
						(arc
							(start 0.254 0.2286)
							(mid 0.239121 0.264521)
							(end 0.2032 0.2794)
						)
					)
					(width 0)
					(fill yes)
				)
			)
		)
	)
	(footprint ""
		(layer "B.Cu")
		(at 74.041 -36.703 90)
		(property "Reference" "R82"
			(at 0 0 90)
			(layer "B.SilkS")
			(hide yes)
			(effects
				(font
					(size 1.27 1.27)
				)
				(justify mirror)
			)
		)
		(property "Value" "10KR2F-2-GP"
			(at -0.064008 -3.993896 90)
			(unlocked yes)
			(layer "B.Fab")
			(hide yes)
			(effects
				(font
					(size 1.016 1.016)
					(thickness 0.1524)
				)
				(justify mirror)
			)
		)
		(property "Device Type" "R402H16"
			(at -0.064008 -5.517896 90)
			(unlocked yes)
			(layer "B.Fab")
			(hide yes)
			(effects
				(font
					(size 1.016 1.016)
					(thickness 0.1524)
				)
				(justify mirror)
			)
		)
		(duplicate_pad_numbers_are_jumpers no)
		(fp_rect
			(start 0.381 0.8382)
			(end -0.381 -0.8382)
			(stroke
				(width 0)
				(type default)
			)
			(fill no)
			(layer "B.CrtYd")
		)
		(fp_rect
			(start 0.381 0.8382)
			(end -0.381 -0.8382)
			(stroke
				(width 0)
				(type default)
			)
			(fill no)
			(layer "B.Fab")
		)
		(pad "1" smd custom
			(at 0 -0.4318 270)
			(size 0.127 0.127)
			(layers "B.Cu" "B.Mask" "B.Paste")
			(net "P3V3")
			(options
				(clearance outline)
				(anchor circle)
			)
			(primitives
				(gr_poly
					(pts
						(arc
							(start -0.2032 0.2794)
							(mid -0.239121 0.264521)
							(end -0.254 0.2286)
						)
						(arc
							(start -0.254 -0.2286)
							(mid -0.239121 -0.264521)
							(end -0.2032 -0.2794)
						)
						(arc
							(start 0.2032 -0.2794)
							(mid 0.239121 -0.264521)
							(end 0.254 -0.2286)
						)
						(arc
							(start 0.254 0.2286)
							(mid 0.239121 0.264521)
							(end 0.2032 0.2794)
						)
					)
					(width 0)
					(fill yes)
				)
			)
		)
		(pad "2" smd custom
			(at 0 0.4318 270)
			(size 0.127 0.127)
			(layers "B.Cu" "B.Mask" "B.Paste")
			(net "FLEX_CLK_SE1")
			(options
				(clearance outline)
				(anchor circle)
			)
			(primitives
				(gr_poly
					(pts
						(arc
							(start -0.2032 0.2794)
							(mid -0.239121 0.264521)
							(end -0.254 0.2286)
						)
						(arc
							(start -0.254 -0.2286)
							(mid -0.239121 -0.264521)
							(end -0.2032 -0.2794)
						)
						(arc
							(start 0.2032 -0.2794)
							(mid 0.239121 -0.264521)
							(end 0.254 -0.2286)
						)
						(arc
							(start 0.254 0.2286)
							(mid 0.239121 0.264521)
							(end 0.2032 0.2794)
						)
					)
					(width 0)
					(fill yes)
				)
			)
		)
	)
	(footprint ""
		(layer "B.Cu")
		(at 85.598 -33.274 90)
		(property "Reference" "R345"
			(at 0 0 90)
			(layer "B.SilkS")
			(hide yes)
			(effects
				(font
					(size 1.27 1.27)
				)
				(justify mirror)
			)
		)
		(property "Value" "100R3F-1-GP"
			(at 0.0254 -2.5146 90)
			(unlocked yes)
			(layer "B.Fab")
			(hide yes)
			(effects
				(font
					(size 1.016 1.016)
					(thickness 0.1524)
				)
				(justify mirror)
			)
		)
		(property "Device Type" "R603H22"
			(at 0.0254 -4.0386 90)
			(unlocked yes)
			(layer "B.Fab")
			(hide yes)
			(effects
				(font
					(size 1.016 1.016)
					(thickness 0.1524)
				)
				(justify mirror)
			)
		)
		(duplicate_pad_numbers_are_jumpers no)
		(fp_line
			(start 0.2032 0)
			(end 0.4191 0)
			(stroke
				(width 0.2032)
				(type default)
			)
			(layer "B.SilkS")
		)
		(fp_line
			(start -0.4318 0)
			(end -0.2032 0)
			(stroke
				(width 0.2032)
				(type default)
			)
			(layer "B.SilkS")
		)
		(fp_rect
			(start 0.635 1.1811)
			(end -0.635 -1.1811)
			(stroke
				(width 0)
				(type default)
			)
			(fill no)
			(layer "B.CrtYd")
		)
		(fp_rect
			(start 0.635 1.1811)
			(end -0.635 -1.1811)
			(stroke
				(width 0)
				(type default)
			)
			(fill no)
			(layer "B.Fab")
		)
		(pad "1" smd custom
			(at 0 -0.6604 270)
			(size 0.19685 0.19685)
			(layers "B.Cu" "B.Mask" "B.Paste")
			(net "SATA3_OBS_P")
			(options
				(clearance outline)
				(anchor circle)
			)
			(primitives
				(gr_poly
					(pts
						(arc
							(start 0.508 0.2921)
							(mid 0.478242 0.363942)
							(end 0.4064 0.3937)
						)
						(arc
							(start -0.4064 0.3937)
							(mid -0.478242 0.363942)
							(end -0.508 0.2921)
						)
						(arc
							(start -0.508 -0.2921)
							(mid -0.478242 -0.363942)
							(end -0.4064 -0.3937)
						)
						(arc
							(start 0.4064 -0.3937)
							(mid 0.478242 -0.363942)
							(end 0.508 -0.2921)
						)
					)
					(width 0)
					(fill yes)
				)
			)
		)
		(pad "2" smd custom
			(at 0 0.6604 270)
			(size 0.19685 0.19685)
			(layers "B.Cu" "B.Mask" "B.Paste")
			(net "SATA3_OBS_N")
			(options
				(clearance outline)
				(anchor circle)
			)
			(primitives
				(gr_poly
					(pts
						(arc
							(start 0.508 0.2921)
							(mid 0.478242 0.363942)
							(end 0.4064 0.3937)
						)
						(arc
							(start -0.4064 0.3937)
							(mid -0.478242 0.363942)
							(end -0.508 0.2921)
						)
						(arc
							(start -0.508 -0.2921)
							(mid -0.478242 -0.363942)
							(end -0.4064 -0.3937)
						)
						(arc
							(start 0.4064 -0.3937)
							(mid 0.478242 -0.363942)
							(end 0.508 -0.2921)
						)
					)
					(width 0)
					(fill yes)
				)
			)
		)
	)
)
